FILE_TYPE = MULTI_PHYS_TABLE;

PART 'MAX11617EEET'

{========================================================================================}
:VALUE           | PART_TYPE | MATERIAL | PART_NUMBER    = STANDARD | LIFECYCLE          | PART_NUMBER   | JEDEC_TYPE              | DESCRIPTION                      | MANUFTR | MANUF_PN        | RD_CMPLS_LVL | CMPLS_LVL | FROM_PJ      | CLASS | DIP_SMD | DATA                    | EE_CHECK_LIST | FP_ECN              | PSL | CREATOR | STATUS | MSD | ESD_CDM | ESD_HBM | ESD_MM | PIN_LENGTH_SHORT_PIN | PIN_LENGTH_LONG_PIN | CREATEDAY  ;
{========================================================================================}
 'MAX11617EEE+T' | 'SMLF'    | 'IC'     | 'AL011617W00'(!) = ''       | ''               | 'AL011617W00' |'QSOP16_0-635_4-9X3-89'| 'IC CTRL(16P)MAX11617EEE+T QSOP' | 'MAM'   | 'MAX11617EEE+T' | 'EP(V1)'     | 'EP(V1)'  | 'F0CE-JAMES' | 'IC'  | ''      | 'MAM_MAX11617EEE+T.pdf' | ''            | 'MAX11617EEE+T.msg' | ''  | ''      | ''     | ''  | ''      | ''      | ''     | '0 MILS'             | '0 MILS'            | '20210528'
 'MAX11617EEE+T' | 'SMLF'    | 'EMPTY'  | 'AL011617W00'(!) = ''       | ''               | 'AL011617W00' |'QSOP16_0-635_4-9X3-89'| 'IC CTRL(16P)MAX11617EEE+T QSOP' | 'MAM'   | 'MAX11617EEE+T' | 'EP(V1)'     | 'EP(V1)'  | 'F0CE-JAMES' | 'IC'  | ''      | 'MAM_MAX11617EEE+T.pdf' | ''            | 'MAX11617EEE+T.msg' | ''  | ''      | ''     | ''  | ''      | ''      | ''     | '0 MILS'             | '0 MILS'            | '20210528'

END_PART

END.

